(kicad_pcb
	(version 20260206)
	(generator "pcbnew")
	(generator_version "10.0")
	(general
		(thickness 1.6)
		(legacy_teardrops no)
	)
	(paper "A4")
	(title_block
		(title "01162023_DA0F0TEBIF0_F0T_Expander_BD_F_brd_V02_OCP.brd")
		(comment 1 "Grand Teton / footprints 5407-5409 of 9728")
	)
	(layers
		(0 "F.Cu" signal "TOP")
		(4 "In1.Cu" signal "GND")
		(6 "In2.Cu" signal "VCC")
		(8 "In3.Cu" signal "VCC1")
		(10 "In4.Cu" signal "GND1")
		(12 "In5.Cu" signal "IN1")
		(14 "In6.Cu" signal "GND2")
		(16 "In7.Cu" signal "IN2")
		(18 "In8.Cu" signal "GND3")
		(20 "In9.Cu" signal "IN3")
		(22 "In10.Cu" signal "GND4")
		(24 "In11.Cu" signal "IN4")
		(26 "In12.Cu" signal "GND5")
		(28 "In13.Cu" signal "IN5")
		(30 "In14.Cu" signal "GND6")
		(32 "In15.Cu" signal "IN6")
		(34 "In16.Cu" signal "GND7")
		(2 "B.Cu" signal "BOTTOM")
		(9 "F.Adhes" user "F.Adhesive")
		(11 "B.Adhes" user "B.Adhesive")
		(13 "F.Paste" user "Package Geometry/Pastemask Top")
		(15 "B.Paste" user "Package Geometry/Pastemask Bottom")
		(5 "F.SilkS" user "Ref Des/Silkscreen Top")
		(7 "B.SilkS" user "Ref Des/Silkscreen Bottom")
		(1 "F.Mask" user "Board Geometry/Soldermask Top")
		(3 "B.Mask" user "Board Geometry/Soldermask Bottom")
		(17 "Dwgs.User" user "User.Drawings")
		(19 "Cmts.User" user "User.Comments")
		(21 "Eco1.User" user "User.Eco1")
		(23 "Eco2.User" user "User.Eco2")
		(25 "Edge.Cuts" user "Board Geometry/Outline")
		(27 "Margin" user)
		(31 "F.CrtYd" user "Package Geometry/Place Bound Top")
		(29 "B.CrtYd" user "Package Geometry/Place Bound Bottom")
		(35 "F.Fab" user "Ref Des/Assembly Top")
		(33 "B.Fab" user "Ref Des/Assembly Bottom")
	)
	(footprint ""
		(layer "F.Cu")
		(at 426.543724 -48.93691 180)
		(property "Reference" "R666"
			(at 0 0 180)
			(layer "F.SilkS")
			(hide yes)
			(effects
				(font
					(size 1.27 1.27)
				)
			)
		)
		(property "Value" ""
			(at 0 0 180)
			(layer "F.Fab")
			(effects
				(font
					(size 1.27 1.27)
				)
			)
		)
		(duplicate_pad_numbers_are_jumpers no)
		(fp_line
			(start 0.7874 0.4064)
			(end -0.7874 0.4064)
			(stroke
				(width 0.1524)
				(type default)
			)
			(layer "F.SilkS")
		)
		(fp_line
			(start 0.7874 -0.4064)
			(end 0.7874 0.4064)
			(stroke
				(width 0.1524)
				(type default)
			)
			(layer "F.SilkS")
		)
		(fp_line
			(start -0.7874 0.4064)
			(end -0.7874 -0.4064)
			(stroke
				(width 0.1524)
				(type default)
			)
			(layer "F.SilkS")
		)
		(fp_line
			(start -0.7874 -0.4064)
			(end 0.7874 -0.4064)
			(stroke
				(width 0.1524)
				(type default)
			)
			(layer "F.SilkS")
		)
		(fp_line
			(start 0.67945 0.3048)
			(end 0.120396 0.3048)
			(stroke
				(width 0.1)
				(type default)
			)
			(layer "F.Fab")
		)
		(fp_line
			(start 0.67945 -0.3048)
			(end 0.67945 0.3048)
			(stroke
				(width 0.1)
				(type default)
			)
			(layer "F.Fab")
		)
		(fp_line
			(start 0.12065 -0.2794)
			(end 0.12065 -0.3048)
			(stroke
				(width 0.1)
				(type default)
			)
			(layer "F.Fab")
		)
		(fp_line
			(start 0.12065 -0.3048)
			(end 0.67945 -0.3048)
			(stroke
				(width 0.1)
				(type default)
			)
			(layer "F.Fab")
		)
		(fp_line
			(start 0.120396 0.3048)
			(end 0.120396 0.2794)
			(stroke
				(width 0.1)
				(type default)
			)
			(layer "F.Fab")
		)
		(fp_line
			(start 0.120396 0.2794)
			(end -0.12065 0.2794)
			(stroke
				(width 0.1)
				(type default)
			)
			(layer "F.Fab")
		)
		(fp_line
			(start -0.12065 0.3048)
			(end -0.67945 0.3048)
			(stroke
				(width 0.1)
				(type default)
			)
			(layer "F.Fab")
		)
		(fp_line
			(start -0.12065 0.2794)
			(end -0.12065 0.3048)
			(stroke
				(width 0.1)
				(type default)
			)
			(layer "F.Fab")
		)
		(fp_line
			(start -0.12065 -0.2794)
			(end 0.12065 -0.2794)
			(stroke
				(width 0.1)
				(type default)
			)
			(layer "F.Fab")
		)
		(fp_line
			(start -0.12065 -0.305054)
			(end -0.12065 -0.2794)
			(stroke
				(width 0.1)
				(type default)
			)
			(layer "F.Fab")
		)
		(fp_line
			(start -0.67945 0.3048)
			(end -0.67945 -0.305054)
			(stroke
				(width 0.1)
				(type default)
			)
			(layer "F.Fab")
		)
		(fp_line
			(start -0.67945 -0.305054)
			(end -0.12065 -0.305054)
			(stroke
				(width 0.1)
				(type default)
			)
			(layer "F.Fab")
		)
		(pad "1" smd circle
			(at -0.40005 0 180)
			(size 0 0)
			(layers "F.Cu" "F.Mask" "F.Paste")
			(net "SMB_BIC_I2C6_MUX_SSD_8_15_ADC_R_SDA")
		)
		(pad "2" smd circle
			(at 0.40005 0 180)
			(size 0 0)
			(layers "F.Cu" "F.Mask" "F.Paste")
			(net "SMB_SSD14_ADC_SDA")
		)
	)
	(footprint ""
		(layer "F.Cu")
		(at 99.35718 -219.559632)
		(property "Reference" "R850"
			(at 0 0 0)
			(layer "F.SilkS")
			(hide yes)
			(effects
				(font
					(size 1.27 1.27)
				)
			)
		)
		(property "Value" ""
			(at 0 0 0)
			(layer "F.Fab")
			(effects
				(font
					(size 1.27 1.27)
				)
			)
		)
		(duplicate_pad_numbers_are_jumpers no)
		(fp_line
			(start -0.7874 -0.4064)
			(end 0.7874 -0.4064)
			(stroke
				(width 0.1524)
				(type default)
			)
			(layer "F.SilkS")
		)
		(fp_line
			(start -0.7874 0.4064)
			(end -0.7874 -0.4064)
			(stroke
				(width 0.1524)
				(type default)
			)
			(layer "F.SilkS")
		)
		(fp_line
			(start 0.7874 -0.4064)
			(end 0.7874 0.4064)
			(stroke
				(width 0.1524)
				(type default)
			)
			(layer "F.SilkS")
		)
		(fp_line
			(start 0.7874 0.4064)
			(end -0.7874 0.4064)
			(stroke
				(width 0.1524)
				(type default)
			)
			(layer "F.SilkS")
		)
		(fp_line
			(start -0.67945 -0.305054)
			(end -0.12065 -0.305054)
			(stroke
				(width 0.1)
				(type default)
			)
			(layer "F.Fab")
		)
		(fp_line
			(start -0.67945 0.3048)
			(end -0.67945 -0.305054)
			(stroke
				(width 0.1)
				(type default)
			)
			(layer "F.Fab")
		)
		(fp_line
			(start -0.12065 -0.305054)
			(end -0.12065 -0.2794)
			(stroke
				(width 0.1)
				(type default)
			)
			(layer "F.Fab")
		)
		(fp_line
			(start -0.12065 -0.2794)
			(end 0.12065 -0.2794)
			(stroke
				(width 0.1)
				(type default)
			)
			(layer "F.Fab")
		)
		(fp_line
			(start -0.12065 0.2794)
			(end -0.12065 0.3048)
			(stroke
				(width 0.1)
				(type default)
			)
			(layer "F.Fab")
		)
		(fp_line
			(start -0.12065 0.3048)
			(end -0.67945 0.3048)
			(stroke
				(width 0.1)
				(type default)
			)
			(layer "F.Fab")
		)
		(fp_line
			(start 0.120396 0.2794)
			(end -0.12065 0.2794)
			(stroke
				(width 0.1)
				(type default)
			)
			(layer "F.Fab")
		)
		(fp_line
			(start 0.120396 0.3048)
			(end 0.120396 0.2794)
			(stroke
				(width 0.1)
				(type default)
			)
			(layer "F.Fab")
		)
		(fp_line
			(start 0.12065 -0.3048)
			(end 0.67945 -0.3048)
			(stroke
				(width 0.1)
				(type default)
			)
			(layer "F.Fab")
		)
		(fp_line
			(start 0.12065 -0.2794)
			(end 0.12065 -0.3048)
			(stroke
				(width 0.1)
				(type default)
			)
			(layer "F.Fab")
		)
		(fp_line
			(start 0.67945 -0.3048)
			(end 0.67945 0.3048)
			(stroke
				(width 0.1)
				(type default)
			)
			(layer "F.Fab")
		)
		(fp_line
			(start 0.67945 0.3048)
			(end 0.120396 0.3048)
			(stroke
				(width 0.1)
				(type default)
			)
			(layer "F.Fab")
		)
		(pad "1" smd circle
			(at -0.40005 0)
			(size 0 0)
			(layers "F.Cu" "F.Mask" "F.Paste")
			(net "P3V3_AUX")
		)
		(pad "2" smd circle
			(at 0.40005 0)
			(size 0 0)
			(layers "F.Cu" "F.Mask" "F.Paste")
			(net "PWR_EN_PEX_R")
		)
	)
	(footprint ""
		(layer "F.Cu")
		(at 10.04316 -45.111924)
		(property "Reference" "R5541"
			(at 0 0 0)
			(layer "F.SilkS")
			(hide yes)
			(effects
				(font
					(size 1.27 1.27)
				)
			)
		)
		(property "Value" ""
			(at 0 0 0)
			(layer "F.Fab")
			(effects
				(font
					(size 1.27 1.27)
				)
			)
		)
		(duplicate_pad_numbers_are_jumpers no)
		(fp_line
			(start -0.7874 -0.4064)
			(end 0.7874 -0.4064)
			(stroke
				(width 0.1524)
				(type default)
			)
			(layer "F.SilkS")
		)
		(fp_line
			(start -0.7874 0.4064)
			(end -0.7874 -0.4064)
			(stroke
				(width 0.1524)
				(type default)
			)
			(layer "F.SilkS")
		)
		(fp_line
			(start 0.7874 -0.4064)
			(end 0.7874 0.4064)
			(stroke
				(width 0.1524)
				(type default)
			)
			(layer "F.SilkS")
		)
		(fp_line
			(start 0.7874 0.4064)
			(end -0.7874 0.4064)
			(stroke
				(width 0.1524)
				(type default)
			)
			(layer "F.SilkS")
		)
		(fp_line
			(start -0.67945 -0.305054)
			(end -0.12065 -0.305054)
			(stroke
				(width 0.1)
				(type default)
			)
			(layer "F.Fab")
		)
		(fp_line
			(start -0.67945 0.3048)
			(end -0.67945 -0.305054)
			(stroke
				(width 0.1)
				(type default)
			)
			(layer "F.Fab")
		)
		(fp_line
			(start -0.12065 -0.305054)
			(end -0.12065 -0.2794)
			(stroke
				(width 0.1)
				(type default)
			)
			(layer "F.Fab")
		)
		(fp_line
			(start -0.12065 -0.2794)
			(end 0.12065 -0.2794)
			(stroke
				(width 0.1)
				(type default)
			)
			(layer "F.Fab")
		)
		(fp_line
			(start -0.12065 0.2794)
			(end -0.12065 0.3048)
			(stroke
				(width 0.1)
				(type default)
			)
			(layer "F.Fab")
		)
		(fp_line
			(start -0.12065 0.3048)
			(end -0.67945 0.3048)
			(stroke
				(width 0.1)
				(type default)
			)
			(layer "F.Fab")
		)
		(fp_line
			(start 0.120396 0.2794)
			(end -0.12065 0.2794)
			(stroke
				(width 0.1)
				(type default)
			)
			(layer "F.Fab")
		)
		(fp_line
			(start 0.120396 0.3048)
			(end 0.120396 0.2794)
			(stroke
				(width 0.1)
				(type default)
			)
			(layer "F.Fab")
		)
		(fp_line
			(start 0.12065 -0.3048)
			(end 0.67945 -0.3048)
			(stroke
				(width 0.1)
				(type default)
			)
			(layer "F.Fab")
		)
		(fp_line
			(start 0.12065 -0.2794)
			(end 0.12065 -0.3048)
			(stroke
				(width 0.1)
				(type default)
			)
			(layer "F.Fab")
		)
		(fp_line
			(start 0.67945 -0.3048)
			(end 0.67945 0.3048)
			(stroke
				(width 0.1)
				(type default)
			)
			(layer "F.Fab")
		)
		(fp_line
			(start 0.67945 0.3048)
			(end 0.120396 0.3048)
			(stroke
				(width 0.1)
				(type default)
			)
			(layer "F.Fab")
		)
		(pad "1" smd circle
			(at -0.40005 0)
			(size 0 0)
			(layers "F.Cu" "F.Mask" "F.Paste")
			(net "SSD0_AUX_P3V3_EN_R")
		)
		(pad "2" smd circle
			(at 0.40005 0)
			(size 0 0)
			(layers "F.Cu" "F.Mask" "F.Paste")
			(net "SSD0_AUX_P3V3_EN")
		)
	)
)
